(kicad_pcb
	(version 20260206)
	(generator "pcbnew")
	(generator_version "10.0")
	(general
		(thickness 1.6)
		(legacy_teardrops no)
	)
	(paper "A4")
	(title_block
		(title "03242023_DA0F0TMBIJ0_F0T_Motherboard_J_brd_V01_OCP.brd")
		(comment 1 "Grand Teton / footprints 984-990 of 6105")
	)
	(layers
		(0 "F.Cu" signal "TOP")
		(4 "In1.Cu" signal "GND")
		(6 "In2.Cu" signal "IN1")
		(8 "In3.Cu" signal "GND1")
		(10 "In4.Cu" signal "IN2")
		(12 "In5.Cu" signal "GND2")
		(14 "In6.Cu" signal "IN3")
		(16 "In7.Cu" signal "GND3")
		(18 "In8.Cu" signal "VCC")
		(20 "In9.Cu" signal "VCC1")
		(22 "In10.Cu" signal "GND4")
		(24 "In11.Cu" signal "IN4")
		(26 "In12.Cu" signal "GND5")
		(28 "In13.Cu" signal "IN5")
		(30 "In14.Cu" signal "GND6")
		(32 "In15.Cu" signal "IN6")
		(34 "In16.Cu" signal "GND7")
		(2 "B.Cu" signal "BOTTOM")
		(9 "F.Adhes" user "F.Adhesive")
		(11 "B.Adhes" user "B.Adhesive")
		(13 "F.Paste" user "Package Geometry/Pastemask Top")
		(15 "B.Paste" user "Package Geometry/Pastemask Bottom")
		(5 "F.SilkS" user "Ref Des/Silkscreen Top")
		(7 "B.SilkS" user "Ref Des/Silkscreen Bottom")
		(1 "F.Mask" user "Board Geometry/Soldermask Top")
		(3 "B.Mask" user "Board Geometry/Soldermask Bottom")
		(17 "Dwgs.User" user "User.Drawings")
		(19 "Cmts.User" user "User.Comments")
		(21 "Eco1.User" user "User.Eco1")
		(23 "Eco2.User" user "User.Eco2")
		(25 "Edge.Cuts" user "Board Geometry/Outline")
		(27 "Margin" user)
		(31 "F.CrtYd" user "Package Geometry/Place Bound Top")
		(29 "B.CrtYd" user "Package Geometry/Place Bound Bottom")
		(35 "F.Fab" user "Ref Des/Assembly Top")
		(33 "B.Fab" user "Ref Des/Assembly Bottom")
	)
	(footprint ""
		(layer "F.Cu")
		(at 82.462624 -347.520514 -90)
		(property "Reference" "PC488"
			(at 0 0 270)
			(layer "F.SilkS")
			(hide yes)
			(effects
				(font
					(size 1.27 1.27)
				)
			)
		)
		(property "Value" ""
			(at 0 0 270)
			(layer "F.Fab")
			(effects
				(font
					(size 1.27 1.27)
				)
			)
		)
		(duplicate_pad_numbers_are_jumpers no)
		(fp_line
			(start -0.7874 0.4064)
			(end -0.7874 -0.4064)
			(stroke
				(width 0.1524)
				(type default)
			)
			(layer "F.SilkS")
		)
		(fp_line
			(start 0.7874 0.4064)
			(end -0.7874 0.4064)
			(stroke
				(width 0.1524)
				(type default)
			)
			(layer "F.SilkS")
		)
		(fp_line
			(start -0.7874 -0.4064)
			(end 0.7874 -0.4064)
			(stroke
				(width 0.1524)
				(type default)
			)
			(layer "F.SilkS")
		)
		(fp_line
			(start 0.7874 -0.4064)
			(end 0.7874 0.4064)
			(stroke
				(width 0.1524)
				(type default)
			)
			(layer "F.SilkS")
		)
		(fp_line
			(start -0.67945 0.3048)
			(end -0.67945 -0.305054)
			(stroke
				(width 0.1)
				(type default)
			)
			(layer "F.Fab")
		)
		(fp_line
			(start -0.12065 0.3048)
			(end -0.67945 0.3048)
			(stroke
				(width 0.1)
				(type default)
			)
			(layer "F.Fab")
		)
		(fp_line
			(start 0.120396 0.3048)
			(end 0.120396 0.2794)
			(stroke
				(width 0.1)
				(type default)
			)
			(layer "F.Fab")
		)
		(fp_line
			(start 0.67945 0.3048)
			(end 0.120396 0.3048)
			(stroke
				(width 0.1)
				(type default)
			)
			(layer "F.Fab")
		)
		(fp_line
			(start -0.12065 0.2794)
			(end -0.12065 0.3048)
			(stroke
				(width 0.1)
				(type default)
			)
			(layer "F.Fab")
		)
		(fp_line
			(start 0.120396 0.2794)
			(end -0.12065 0.2794)
			(stroke
				(width 0.1)
				(type default)
			)
			(layer "F.Fab")
		)
		(fp_line
			(start -0.12065 -0.2794)
			(end 0.12065 -0.2794)
			(stroke
				(width 0.1)
				(type default)
			)
			(layer "F.Fab")
		)
		(fp_line
			(start 0.12065 -0.2794)
			(end 0.12065 -0.3048)
			(stroke
				(width 0.1)
				(type default)
			)
			(layer "F.Fab")
		)
		(fp_line
			(start 0.12065 -0.3048)
			(end 0.67945 -0.3048)
			(stroke
				(width 0.1)
				(type default)
			)
			(layer "F.Fab")
		)
		(fp_line
			(start 0.67945 -0.3048)
			(end 0.67945 0.3048)
			(stroke
				(width 0.1)
				(type default)
			)
			(layer "F.Fab")
		)
		(fp_line
			(start -0.67945 -0.305054)
			(end -0.12065 -0.305054)
			(stroke
				(width 0.1)
				(type default)
			)
			(layer "F.Fab")
		)
		(fp_line
			(start -0.12065 -0.305054)
			(end -0.12065 -0.2794)
			(stroke
				(width 0.1)
				(type default)
			)
			(layer "F.Fab")
		)
		(pad "1" smd circle
			(at -0.40005 0 270)
			(size 0 0)
			(layers "F.Cu" "F.Mask" "F.Paste")
			(net "SW_PVCCIN_CPU1_BOOT7_R")
		)
		(pad "2" smd circle
			(at 0.40005 0 270)
			(size 0 0)
			(layers "F.Cu" "F.Mask" "F.Paste")
			(net "SW_PVCCIN_CPU1_BOOTR7")
		)
	)
	(footprint ""
		(layer "F.Cu")
		(at 109.00537 -337.830668)
		(property "Reference" "PC560_P1_2"
			(at 0 0 0)
			(layer "F.SilkS")
			(hide yes)
			(effects
				(font
					(size 1.27 1.27)
				)
			)
		)
		(property "Value" ""
			(at 0 0 0)
			(layer "F.Fab")
			(effects
				(font
					(size 1.27 1.27)
				)
			)
		)
		(duplicate_pad_numbers_are_jumpers no)
		(fp_line
			(start -0.7874 -0.4064)
			(end 0.7874 -0.4064)
			(stroke
				(width 0.1524)
				(type default)
			)
			(layer "F.SilkS")
		)
		(fp_line
			(start -0.7874 0.4064)
			(end -0.7874 -0.4064)
			(stroke
				(width 0.1524)
				(type default)
			)
			(layer "F.SilkS")
		)
		(fp_line
			(start 0.7874 -0.4064)
			(end 0.7874 0.4064)
			(stroke
				(width 0.1524)
				(type default)
			)
			(layer "F.SilkS")
		)
		(fp_line
			(start 0.7874 0.4064)
			(end -0.7874 0.4064)
			(stroke
				(width 0.1524)
				(type default)
			)
			(layer "F.SilkS")
		)
		(fp_line
			(start -0.67945 -0.305054)
			(end -0.12065 -0.305054)
			(stroke
				(width 0.1)
				(type default)
			)
			(layer "F.Fab")
		)
		(fp_line
			(start -0.67945 0.3048)
			(end -0.67945 -0.305054)
			(stroke
				(width 0.1)
				(type default)
			)
			(layer "F.Fab")
		)
		(fp_line
			(start -0.12065 -0.305054)
			(end -0.12065 -0.2794)
			(stroke
				(width 0.1)
				(type default)
			)
			(layer "F.Fab")
		)
		(fp_line
			(start -0.12065 -0.2794)
			(end 0.12065 -0.2794)
			(stroke
				(width 0.1)
				(type default)
			)
			(layer "F.Fab")
		)
		(fp_line
			(start -0.12065 0.2794)
			(end -0.12065 0.3048)
			(stroke
				(width 0.1)
				(type default)
			)
			(layer "F.Fab")
		)
		(fp_line
			(start -0.12065 0.3048)
			(end -0.67945 0.3048)
			(stroke
				(width 0.1)
				(type default)
			)
			(layer "F.Fab")
		)
		(fp_line
			(start 0.120396 0.2794)
			(end -0.12065 0.2794)
			(stroke
				(width 0.1)
				(type default)
			)
			(layer "F.Fab")
		)
		(fp_line
			(start 0.120396 0.3048)
			(end 0.120396 0.2794)
			(stroke
				(width 0.1)
				(type default)
			)
			(layer "F.Fab")
		)
		(fp_line
			(start 0.12065 -0.3048)
			(end 0.67945 -0.3048)
			(stroke
				(width 0.1)
				(type default)
			)
			(layer "F.Fab")
		)
		(fp_line
			(start 0.12065 -0.2794)
			(end 0.12065 -0.3048)
			(stroke
				(width 0.1)
				(type default)
			)
			(layer "F.Fab")
		)
		(fp_line
			(start 0.67945 -0.3048)
			(end 0.67945 0.3048)
			(stroke
				(width 0.1)
				(type default)
			)
			(layer "F.Fab")
		)
		(fp_line
			(start 0.67945 0.3048)
			(end 0.120396 0.3048)
			(stroke
				(width 0.1)
				(type default)
			)
			(layer "F.Fab")
		)
		(pad "1" smd circle
			(at -0.40005 0)
			(size 0 0)
			(layers "F.Cu" "F.Mask" "F.Paste")
			(net "SW_P12V_PVCCIN_CPU1_FLT")
		)
		(pad "2" smd circle
			(at 0.40005 0)
			(size 0 0)
			(layers "F.Cu" "F.Mask" "F.Paste")
			(net "GND")
		)
	)
	(footprint ""
		(layer "F.Cu")
		(at 362.49737 -355.340666 -90)
		(property "Reference" "PR345"
			(at 0 0 270)
			(layer "F.SilkS")
			(hide yes)
			(effects
				(font
					(size 1.27 1.27)
				)
			)
		)
		(property "Value" ""
			(at 0 0 270)
			(layer "F.Fab")
			(effects
				(font
					(size 1.27 1.27)
				)
			)
		)
		(duplicate_pad_numbers_are_jumpers no)
		(fp_line
			(start -0.7874 0.4064)
			(end -0.7874 -0.4064)
			(stroke
				(width 0.1524)
				(type default)
			)
			(layer "F.SilkS")
		)
		(fp_line
			(start 0.7874 0.4064)
			(end -0.7874 0.4064)
			(stroke
				(width 0.1524)
				(type default)
			)
			(layer "F.SilkS")
		)
		(fp_line
			(start -0.7874 -0.4064)
			(end 0.7874 -0.4064)
			(stroke
				(width 0.1524)
				(type default)
			)
			(layer "F.SilkS")
		)
		(fp_line
			(start 0.7874 -0.4064)
			(end 0.7874 0.4064)
			(stroke
				(width 0.1524)
				(type default)
			)
			(layer "F.SilkS")
		)
		(fp_line
			(start -0.67945 0.3048)
			(end -0.67945 -0.305054)
			(stroke
				(width 0.1)
				(type default)
			)
			(layer "F.Fab")
		)
		(fp_line
			(start -0.12065 0.3048)
			(end -0.67945 0.3048)
			(stroke
				(width 0.1)
				(type default)
			)
			(layer "F.Fab")
		)
		(fp_line
			(start 0.120396 0.3048)
			(end 0.120396 0.2794)
			(stroke
				(width 0.1)
				(type default)
			)
			(layer "F.Fab")
		)
		(fp_line
			(start 0.67945 0.3048)
			(end 0.120396 0.3048)
			(stroke
				(width 0.1)
				(type default)
			)
			(layer "F.Fab")
		)
		(fp_line
			(start -0.12065 0.2794)
			(end -0.12065 0.3048)
			(stroke
				(width 0.1)
				(type default)
			)
			(layer "F.Fab")
		)
		(fp_line
			(start 0.120396 0.2794)
			(end -0.12065 0.2794)
			(stroke
				(width 0.1)
				(type default)
			)
			(layer "F.Fab")
		)
		(fp_line
			(start -0.12065 -0.2794)
			(end 0.12065 -0.2794)
			(stroke
				(width 0.1)
				(type default)
			)
			(layer "F.Fab")
		)
		(fp_line
			(start 0.12065 -0.2794)
			(end 0.12065 -0.3048)
			(stroke
				(width 0.1)
				(type default)
			)
			(layer "F.Fab")
		)
		(fp_line
			(start 0.12065 -0.3048)
			(end 0.67945 -0.3048)
			(stroke
				(width 0.1)
				(type default)
			)
			(layer "F.Fab")
		)
		(fp_line
			(start 0.67945 -0.3048)
			(end 0.67945 0.3048)
			(stroke
				(width 0.1)
				(type default)
			)
			(layer "F.Fab")
		)
		(fp_line
			(start -0.67945 -0.305054)
			(end -0.12065 -0.305054)
			(stroke
				(width 0.1)
				(type default)
			)
			(layer "F.Fab")
		)
		(fp_line
			(start -0.12065 -0.305054)
			(end -0.12065 -0.2794)
			(stroke
				(width 0.1)
				(type default)
			)
			(layer "F.Fab")
		)
		(pad "1" smd circle
			(at -0.40005 0 270)
			(size 0 0)
			(layers "F.Cu" "F.Mask" "F.Paste")
			(net "SH_PVCCFA_EHV_FIVRA_CPU0")
		)
		(pad "2" smd circle
			(at 0.40005 0 270)
			(size 0 0)
			(layers "F.Cu" "F.Mask" "F.Paste")
			(net "SH_PVCCFA_EHV_FIVRA_CPU0_R")
		)
	)
	(footprint ""
		(layer "F.Cu")
		(at 255.45669 -39.482522 -90)
		(property "Reference" "PC2215"
			(at 0 0 270)
			(layer "F.SilkS")
			(hide yes)
			(effects
				(font
					(size 1.27 1.27)
				)
			)
		)
		(property "Value" ""
			(at 0 0 270)
			(layer "F.Fab")
			(effects
				(font
					(size 1.27 1.27)
				)
			)
		)
		(duplicate_pad_numbers_are_jumpers no)
		(fp_line
			(start -0.7874 0.4064)
			(end -0.7874 -0.4064)
			(stroke
				(width 0.1524)
				(type default)
			)
			(layer "F.SilkS")
		)
		(fp_line
			(start 0.7874 0.4064)
			(end -0.7874 0.4064)
			(stroke
				(width 0.1524)
				(type default)
			)
			(layer "F.SilkS")
		)
		(fp_line
			(start -0.7874 -0.4064)
			(end 0.7874 -0.4064)
			(stroke
				(width 0.1524)
				(type default)
			)
			(layer "F.SilkS")
		)
		(fp_line
			(start 0.7874 -0.4064)
			(end 0.7874 0.4064)
			(stroke
				(width 0.1524)
				(type default)
			)
			(layer "F.SilkS")
		)
		(fp_line
			(start -0.67945 0.3048)
			(end -0.67945 -0.305054)
			(stroke
				(width 0.1)
				(type default)
			)
			(layer "F.Fab")
		)
		(fp_line
			(start -0.12065 0.3048)
			(end -0.67945 0.3048)
			(stroke
				(width 0.1)
				(type default)
			)
			(layer "F.Fab")
		)
		(fp_line
			(start 0.120396 0.3048)
			(end 0.120396 0.2794)
			(stroke
				(width 0.1)
				(type default)
			)
			(layer "F.Fab")
		)
		(fp_line
			(start 0.67945 0.3048)
			(end 0.120396 0.3048)
			(stroke
				(width 0.1)
				(type default)
			)
			(layer "F.Fab")
		)
		(fp_line
			(start -0.12065 0.2794)
			(end -0.12065 0.3048)
			(stroke
				(width 0.1)
				(type default)
			)
			(layer "F.Fab")
		)
		(fp_line
			(start 0.120396 0.2794)
			(end -0.12065 0.2794)
			(stroke
				(width 0.1)
				(type default)
			)
			(layer "F.Fab")
		)
		(fp_line
			(start -0.12065 -0.2794)
			(end 0.12065 -0.2794)
			(stroke
				(width 0.1)
				(type default)
			)
			(layer "F.Fab")
		)
		(fp_line
			(start 0.12065 -0.2794)
			(end 0.12065 -0.3048)
			(stroke
				(width 0.1)
				(type default)
			)
			(layer "F.Fab")
		)
		(fp_line
			(start 0.12065 -0.3048)
			(end 0.67945 -0.3048)
			(stroke
				(width 0.1)
				(type default)
			)
			(layer "F.Fab")
		)
		(fp_line
			(start 0.67945 -0.3048)
			(end 0.67945 0.3048)
			(stroke
				(width 0.1)
				(type default)
			)
			(layer "F.Fab")
		)
		(fp_line
			(start -0.67945 -0.305054)
			(end -0.12065 -0.305054)
			(stroke
				(width 0.1)
				(type default)
			)
			(layer "F.Fab")
		)
		(fp_line
			(start -0.12065 -0.305054)
			(end -0.12065 -0.2794)
			(stroke
				(width 0.1)
				(type default)
			)
			(layer "F.Fab")
		)
		(pad "1" smd circle
			(at -0.40005 0 270)
			(size 0 0)
			(layers "F.Cu" "F.Mask" "F.Paste")
			(net "P12V_E1S_GATE_0")
		)
		(pad "2" smd circle
			(at 0.40005 0 270)
			(size 0 0)
			(layers "F.Cu" "F.Mask" "F.Paste")
			(net "GND")
		)
	)
	(footprint ""
		(layer "F.Cu")
		(at 186.8678 -358.14635)
		(property "Reference" "PC726_P1_3"
			(at 0 0 0)
			(layer "F.SilkS")
			(hide yes)
			(effects
				(font
					(size 1.27 1.27)
				)
			)
		)
		(property "Value" ""
			(at 0 0 0)
			(layer "F.Fab")
			(effects
				(font
					(size 1.27 1.27)
				)
			)
		)
		(duplicate_pad_numbers_are_jumpers no)
		(fp_line
			(start -1.524 -0.762)
			(end 1.524 -0.762)
			(stroke
				(width 0.1524)
				(type default)
			)
			(layer "F.SilkS")
		)
		(fp_line
			(start -1.524 0.762)
			(end -1.524 -0.762)
			(stroke
				(width 0.1524)
				(type default)
			)
			(layer "F.SilkS")
		)
		(fp_line
			(start 1.524 -0.762)
			(end 1.524 0.762)
			(stroke
				(width 0.1524)
				(type default)
			)
			(layer "F.SilkS")
		)
		(fp_line
			(start 1.524 0.762)
			(end -1.524 0.762)
			(stroke
				(width 0.1524)
				(type default)
			)
			(layer "F.SilkS")
		)
		(fp_line
			(start -1.1049 -0.724916)
			(end -1.1049 0.724916)
			(stroke
				(width 0.1)
				(type default)
			)
			(layer "F.Fab")
		)
		(fp_line
			(start -1.1049 0.724916)
			(end 1.1049 0.724916)
			(stroke
				(width 0.1)
				(type default)
			)
			(layer "F.Fab")
		)
		(fp_line
			(start 1.1049 -0.724916)
			(end -1.1049 -0.724916)
			(stroke
				(width 0.1)
				(type default)
			)
			(layer "F.Fab")
		)
		(fp_line
			(start 1.1049 0.724916)
			(end 1.1049 -0.724916)
			(stroke
				(width 0.1)
				(type default)
			)
			(layer "F.Fab")
		)
		(pad "1" smd rect
			(at -0.889 0 180)
			(size 1.016 1.27)
			(layers "F.Cu" "F.Mask" "F.Paste")
			(net "SW_P12V_PVCCFA_EHV_FIVRA_CPU1_R")
		)
		(pad "2" smd rect
			(at 0.889 0 180)
			(size 1.016 1.27)
			(layers "F.Cu" "F.Mask" "F.Paste")
			(net "GND")
		)
	)
	(footprint ""
		(layer "F.Cu")
		(at 265.64971 -22.29993)
		(property "Reference" "H102"
			(at -4.51104 -5.629148 0)
			(unlocked yes)
			(layer "F.SilkS")
			(effects
				(font
					(size 0.7874 0.5842)
					(thickness 0.1524)
				)
				(justify left)
			)
		)
		(property "Value" ""
			(at 0 0 0)
			(layer "F.Fab")
			(effects
				(font
					(size 1.27 1.27)
				)
			)
		)
		(duplicate_pad_numbers_are_jumpers no)
		(pad "1" thru_hole circle
			(at 0 0)
			(size 10.0076 10.0076)
			(drill 5.6134)
			(layers "*.Cu" "*.Mask")
			(remove_unused_layers no)
			(net "GND")
			(clearance -1.9431)
		)
	)
	(footprint ""
		(layer "F.Cu")
		(at 169.44848 -423.890948)
		(property "Reference" "R2909"
			(at 0 0 0)
			(layer "F.SilkS")
			(hide yes)
			(effects
				(font
					(size 1.27 1.27)
				)
			)
		)
		(property "Value" ""
			(at 0 0 0)
			(layer "F.Fab")
			(effects
				(font
					(size 1.27 1.27)
				)
			)
		)
		(duplicate_pad_numbers_are_jumpers no)
		(fp_line
			(start -0.7874 -0.4064)
			(end 0.7874 -0.4064)
			(stroke
				(width 0.1524)
				(type default)
			)
			(layer "F.SilkS")
		)
		(fp_line
			(start -0.7874 0.4064)
			(end -0.7874 -0.4064)
			(stroke
				(width 0.1524)
				(type default)
			)
			(layer "F.SilkS")
		)
		(fp_line
			(start 0.7874 -0.4064)
			(end 0.7874 0.4064)
			(stroke
				(width 0.1524)
				(type default)
			)
			(layer "F.SilkS")
		)
		(fp_line
			(start 0.7874 0.4064)
			(end -0.7874 0.4064)
			(stroke
				(width 0.1524)
				(type default)
			)
			(layer "F.SilkS")
		)
		(fp_line
			(start -0.67945 -0.305054)
			(end -0.12065 -0.305054)
			(stroke
				(width 0.1)
				(type default)
			)
			(layer "F.Fab")
		)
		(fp_line
			(start -0.67945 0.3048)
			(end -0.67945 -0.305054)
			(stroke
				(width 0.1)
				(type default)
			)
			(layer "F.Fab")
		)
		(fp_line
			(start -0.12065 -0.305054)
			(end -0.12065 -0.2794)
			(stroke
				(width 0.1)
				(type default)
			)
			(layer "F.Fab")
		)
		(fp_line
			(start -0.12065 -0.2794)
			(end 0.12065 -0.2794)
			(stroke
				(width 0.1)
				(type default)
			)
			(layer "F.Fab")
		)
		(fp_line
			(start -0.12065 0.2794)
			(end -0.12065 0.3048)
			(stroke
				(width 0.1)
				(type default)
			)
			(layer "F.Fab")
		)
		(fp_line
			(start -0.12065 0.3048)
			(end -0.67945 0.3048)
			(stroke
				(width 0.1)
				(type default)
			)
			(layer "F.Fab")
		)
		(fp_line
			(start 0.120396 0.2794)
			(end -0.12065 0.2794)
			(stroke
				(width 0.1)
				(type default)
			)
			(layer "F.Fab")
		)
		(fp_line
			(start 0.120396 0.3048)
			(end 0.120396 0.2794)
			(stroke
				(width 0.1)
				(type default)
			)
			(layer "F.Fab")
		)
		(fp_line
			(start 0.12065 -0.3048)
			(end 0.67945 -0.3048)
			(stroke
				(width 0.1)
				(type default)
			)
			(layer "F.Fab")
		)
		(fp_line
			(start 0.12065 -0.2794)
			(end 0.12065 -0.3048)
			(stroke
				(width 0.1)
				(type default)
			)
			(layer "F.Fab")
		)
		(fp_line
			(start 0.67945 -0.3048)
			(end 0.67945 0.3048)
			(stroke
				(width 0.1)
				(type default)
			)
			(layer "F.Fab")
		)
		(fp_line
			(start 0.67945 0.3048)
			(end 0.120396 0.3048)
			(stroke
				(width 0.1)
				(type default)
			)
			(layer "F.Fab")
		)
		(pad "1" smd circle
			(at -0.40005 0)
			(size 0 0)
			(layers "F.Cu" "F.Mask" "F.Paste")
			(net "P3V3_AUX")
		)
		(pad "2" smd circle
			(at 0.40005 0)
			(size 0 0)
			(layers "F.Cu" "F.Mask" "F.Paste")
			(net "RST_SWB_BIC_R_N")
		)
	)
)
